(kicad_pcb
	(version 20260206)
	(generator "pcbnew")
	(generator_version "10.0")
	(general
		(thickness 1.6)
		(legacy_teardrops no)
	)
	(paper "A4")
	(title_block
		(title "04192023_DAF0TMB3IC0_F0TG_MB_C_brd_V02_OCP.brd")
		(comment 1 "Grand Teton / footprint 4248 of 8354 (J33), pads 1-113 of 291")
	)
	(layers
		(0 "F.Cu" signal "TOP")
		(4 "In1.Cu" signal "GND")
		(6 "In2.Cu" signal "IN1")
		(8 "In3.Cu" signal "GND1")
		(10 "In4.Cu" signal "IN2")
		(12 "In5.Cu" signal "GND2")
		(14 "In6.Cu" signal "IN3")
		(16 "In7.Cu" signal "GND3")
		(18 "In8.Cu" signal "VCC")
		(20 "In9.Cu" signal "VCC1")
		(22 "In10.Cu" signal "GND4")
		(24 "In11.Cu" signal "IN4")
		(26 "In12.Cu" signal "GND5")
		(28 "In13.Cu" signal "IN5")
		(30 "In14.Cu" signal "GND6")
		(32 "In15.Cu" signal "IN6")
		(34 "In16.Cu" signal "GND7")
		(2 "B.Cu" signal "BOTTOM")
		(9 "F.Adhes" user "F.Adhesive")
		(11 "B.Adhes" user "B.Adhesive")
		(13 "F.Paste" user "Package Geometry/Pastemask Top")
		(15 "B.Paste" user "Package Geometry/Pastemask Bottom")
		(5 "F.SilkS" user "Ref Des/Silkscreen Top")
		(7 "B.SilkS" user "Ref Des/Silkscreen Bottom")
		(1 "F.Mask" user "Board Geometry/Soldermask Top")
		(3 "B.Mask" user "Board Geometry/Soldermask Bottom")
		(17 "Dwgs.User" user "User.Drawings")
		(19 "Cmts.User" user "User.Comments")
		(21 "Eco1.User" user "User.Eco1")
		(23 "Eco2.User" user "User.Eco2")
		(25 "Edge.Cuts" user "Board Geometry/Outline")
		(27 "Margin" user)
		(31 "F.CrtYd" user "Package Geometry/Place Bound Top")
		(29 "B.CrtYd" user "Package Geometry/Place Bound Bottom")
		(35 "F.Fab" user "Ref Des/Assembly Top")
		(33 "B.Fab" user "Ref Des/Assembly Bottom")
	)
	(footprint ""
		(layer "F.Cu")
		(at 19.658076 -255.560322 180)
		(property "Reference" "J33"
			(at -1.25984 -82.079846 0)
			(unlocked yes)
			(layer "F.SilkS")
			(effects
				(font
					(size 0.7874 0.5842)
					(thickness 0.1524)
				)
			)
		)
		(property "Value" ""
			(at 0 0 180)
			(layer "F.Fab")
			(effects
				(font
					(size 1.27 1.27)
				)
			)
		)
		(duplicate_pad_numbers_are_jumpers no)
		(pad "1" smd rect
			(at -2.050034 -63.324994 90)
			(size 0.519938 1.4986)
			(layers "F.Cu" "F.Mask" "F.Paste")
			(net "P12V_MEM_CPU1")
		)
		(pad "2" smd rect
			(at -2.050034 -62.47511 90)
			(size 0.519938 1.4986)
			(layers "F.Cu" "F.Mask" "F.Paste")
			(net "Net_2326")
		)
		(pad "3" smd rect
			(at -2.050034 -61.624972 90)
			(size 0.519938 1.4986)
			(layers "F.Cu" "F.Mask" "F.Paste")
			(net "P3V3_AUX")
		)
		(pad "4" smd rect
			(at -2.050034 -60.775088 90)
			(size 0.519938 1.4986)
			(layers "F.Cu" "F.Mask" "F.Paste")
			(net "I3C_SPD_DDRF_CPU1_SCL")
		)
		(pad "5" smd rect
			(at -2.050034 -59.92495 90)
			(size 0.519938 1.4986)
			(layers "F.Cu" "F.Mask" "F.Paste")
			(net "I3C_SPD_DDRF_CPU1_SDA")
		)
		(pad "6" smd rect
			(at -2.050034 -59.075066 90)
			(size 0.519938 1.4986)
			(layers "F.Cu" "F.Mask" "F.Paste")
			(net "GND")
		)
		(pad "7" smd rect
			(at -2.050034 -58.224928 90)
			(size 0.519938 1.4986)
			(layers "F.Cu" "F.Mask" "F.Paste")
			(net "M_F_CPU1_SA_DQ<0>")
		)
		(pad "8" smd rect
			(at -2.050034 -57.375044 90)
			(size 0.519938 1.4986)
			(layers "F.Cu" "F.Mask" "F.Paste")
			(net "GND")
		)
		(pad "9" smd rect
			(at -2.050034 -56.524906 90)
			(size 0.519938 1.4986)
			(layers "F.Cu" "F.Mask" "F.Paste")
			(net "M_F_CPU1_SA_DQ<1>")
		)
		(pad "10" smd rect
			(at -2.050034 -55.675022 90)
			(size 0.519938 1.4986)
			(layers "F.Cu" "F.Mask" "F.Paste")
			(net "GND")
		)
		(pad "11" smd rect
			(at -2.050034 -54.824884 90)
			(size 0.519938 1.4986)
			(layers "F.Cu" "F.Mask" "F.Paste")
			(net "M_F_CPU1_SA_DQS_DP<0>")
		)
		(pad "12" smd rect
			(at -2.050034 -53.975 90)
			(size 0.519938 1.4986)
			(layers "F.Cu" "F.Mask" "F.Paste")
			(net "M_F_CPU1_SA_DQS_DN<0>")
		)
		(pad "13" smd rect
			(at -2.050034 -53.125116 90)
			(size 0.519938 1.4986)
			(layers "F.Cu" "F.Mask" "F.Paste")
			(net "GND")
		)
		(pad "14" smd rect
			(at -2.050034 -52.274978 90)
			(size 0.519938 1.4986)
			(layers "F.Cu" "F.Mask" "F.Paste")
			(net "M_F_CPU1_SA_DQ<4>")
		)
		(pad "15" smd rect
			(at -2.050034 -51.425094 90)
			(size 0.519938 1.4986)
			(layers "F.Cu" "F.Mask" "F.Paste")
			(net "GND")
		)
		(pad "16" smd rect
			(at -2.050034 -50.574956 90)
			(size 0.519938 1.4986)
			(layers "F.Cu" "F.Mask" "F.Paste")
			(net "M_F_CPU1_SA_DQ<5>")
		)
		(pad "17" smd rect
			(at -2.050034 -49.725072 90)
			(size 0.519938 1.4986)
			(layers "F.Cu" "F.Mask" "F.Paste")
			(net "GND")
		)
		(pad "18" smd rect
			(at -2.050034 -48.874934 90)
			(size 0.519938 1.4986)
			(layers "F.Cu" "F.Mask" "F.Paste")
			(net "M_F_CPU1_SA_DQ<8>")
		)
		(pad "19" smd rect
			(at -2.050034 -48.02505 90)
			(size 0.519938 1.4986)
			(layers "F.Cu" "F.Mask" "F.Paste")
			(net "GND")
		)
		(pad "20" smd rect
			(at -2.050034 -47.174912 90)
			(size 0.519938 1.4986)
			(layers "F.Cu" "F.Mask" "F.Paste")
			(net "M_F_CPU1_SA_DQ<9>")
		)
		(pad "21" smd rect
			(at -2.050034 -46.325028 90)
			(size 0.519938 1.4986)
			(layers "F.Cu" "F.Mask" "F.Paste")
			(net "GND")
		)
		(pad "22" smd rect
			(at -2.050034 -45.47489 90)
			(size 0.519938 1.4986)
			(layers "F.Cu" "F.Mask" "F.Paste")
			(net "M_F_CPU1_SA_DQS_DP<1>")
		)
		(pad "23" smd rect
			(at -2.050034 -44.625006 90)
			(size 0.519938 1.4986)
			(layers "F.Cu" "F.Mask" "F.Paste")
			(net "M_F_CPU1_SA_DQS_DN<1>")
		)
		(pad "24" smd rect
			(at -2.050034 -43.775122 90)
			(size 0.519938 1.4986)
			(layers "F.Cu" "F.Mask" "F.Paste")
			(net "GND")
		)
		(pad "25" smd rect
			(at -2.050034 -42.924984 90)
			(size 0.519938 1.4986)
			(layers "F.Cu" "F.Mask" "F.Paste")
			(net "M_F_CPU1_SA_DQ<12>")
		)
		(pad "26" smd rect
			(at -2.050034 -42.0751 90)
			(size 0.519938 1.4986)
			(layers "F.Cu" "F.Mask" "F.Paste")
			(net "GND")
		)
		(pad "27" smd rect
			(at -2.050034 -41.224962 90)
			(size 0.519938 1.4986)
			(layers "F.Cu" "F.Mask" "F.Paste")
			(net "M_F_CPU1_SA_DQ<13>")
		)
		(pad "28" smd rect
			(at -2.050034 -40.375078 90)
			(size 0.519938 1.4986)
			(layers "F.Cu" "F.Mask" "F.Paste")
			(net "GND")
		)
		(pad "29" smd rect
			(at -2.050034 -39.52494 90)
			(size 0.519938 1.4986)
			(layers "F.Cu" "F.Mask" "F.Paste")
			(net "M_F_CPU1_SA_DQ<16>")
		)
		(pad "30" smd rect
			(at -2.050034 -38.675056 90)
			(size 0.519938 1.4986)
			(layers "F.Cu" "F.Mask" "F.Paste")
			(net "GND")
		)
		(pad "31" smd rect
			(at -2.050034 -37.824918 90)
			(size 0.519938 1.4986)
			(layers "F.Cu" "F.Mask" "F.Paste")
			(net "M_F_CPU1_SA_DQ<17>")
		)
		(pad "32" smd rect
			(at -2.050034 -36.975034 90)
			(size 0.519938 1.4986)
			(layers "F.Cu" "F.Mask" "F.Paste")
			(net "GND")
		)
		(pad "33" smd rect
			(at -2.050034 -36.124896 90)
			(size 0.519938 1.4986)
			(layers "F.Cu" "F.Mask" "F.Paste")
			(net "M_F_CPU1_SA_DQS_DP<2>")
		)
		(pad "34" smd rect
			(at -2.050034 -35.275012 90)
			(size 0.519938 1.4986)
			(layers "F.Cu" "F.Mask" "F.Paste")
			(net "M_F_CPU1_SA_DQS_DN<2>")
		)
		(pad "35" smd rect
			(at -2.050034 -34.425128 90)
			(size 0.519938 1.4986)
			(layers "F.Cu" "F.Mask" "F.Paste")
			(net "GND")
		)
		(pad "36" smd rect
			(at -2.050034 -33.57499 90)
			(size 0.519938 1.4986)
			(layers "F.Cu" "F.Mask" "F.Paste")
			(net "M_F_CPU1_SA_DQ<20>")
		)
		(pad "37" smd rect
			(at -2.050034 -32.725106 90)
			(size 0.519938 1.4986)
			(layers "F.Cu" "F.Mask" "F.Paste")
			(net "GND")
		)
		(pad "38" smd rect
			(at -2.050034 -31.874968 90)
			(size 0.519938 1.4986)
			(layers "F.Cu" "F.Mask" "F.Paste")
			(net "M_F_CPU1_SA_DQ<21>")
		)
		(pad "39" smd rect
			(at -2.050034 -31.025084 90)
			(size 0.519938 1.4986)
			(layers "F.Cu" "F.Mask" "F.Paste")
			(net "GND")
		)
		(pad "40" smd rect
			(at -2.050034 -30.174946 90)
			(size 0.519938 1.4986)
			(layers "F.Cu" "F.Mask" "F.Paste")
			(net "M_F_CPU1_SA_DQ<24>")
		)
		(pad "41" smd rect
			(at -2.050034 -29.325062 90)
			(size 0.519938 1.4986)
			(layers "F.Cu" "F.Mask" "F.Paste")
			(net "GND")
		)
		(pad "42" smd rect
			(at -2.050034 -28.474924 90)
			(size 0.519938 1.4986)
			(layers "F.Cu" "F.Mask" "F.Paste")
			(net "M_F_CPU1_SA_DQ<25>")
		)
		(pad "43" smd rect
			(at -2.050034 -27.62504 90)
			(size 0.519938 1.4986)
			(layers "F.Cu" "F.Mask" "F.Paste")
			(net "GND")
		)
		(pad "44" smd rect
			(at -2.050034 -26.774902 90)
			(size 0.519938 1.4986)
			(layers "F.Cu" "F.Mask" "F.Paste")
			(net "M_F_CPU1_SA_DQS_DP<3>")
		)
		(pad "45" smd rect
			(at -2.050034 -25.925018 90)
			(size 0.519938 1.4986)
			(layers "F.Cu" "F.Mask" "F.Paste")
			(net "M_F_CPU1_SA_DQS_DN<3>")
		)
		(pad "46" smd rect
			(at -2.050034 -25.07488 90)
			(size 0.519938 1.4986)
			(layers "F.Cu" "F.Mask" "F.Paste")
			(net "GND")
		)
		(pad "47" smd rect
			(at -2.050034 -24.224996 90)
			(size 0.519938 1.4986)
			(layers "F.Cu" "F.Mask" "F.Paste")
			(net "M_F_CPU1_SA_DQ<28>")
		)
		(pad "48" smd rect
			(at -2.050034 -23.375112 90)
			(size 0.519938 1.4986)
			(layers "F.Cu" "F.Mask" "F.Paste")
			(net "GND")
		)
		(pad "49" smd rect
			(at -2.050034 -22.524974 90)
			(size 0.519938 1.4986)
			(layers "F.Cu" "F.Mask" "F.Paste")
			(net "M_F_CPU1_SA_DQ<29>")
		)
		(pad "50" smd rect
			(at -2.050034 -21.67509 90)
			(size 0.519938 1.4986)
			(layers "F.Cu" "F.Mask" "F.Paste")
			(net "GND")
		)
		(pad "51" smd rect
			(at -2.050034 -20.824952 90)
			(size 0.519938 1.4986)
			(layers "F.Cu" "F.Mask" "F.Paste")
			(net "M_F_CPU1_SA_CB<0>")
		)
		(pad "52" smd rect
			(at -2.050034 -19.975068 90)
			(size 0.519938 1.4986)
			(layers "F.Cu" "F.Mask" "F.Paste")
			(net "GND")
		)
		(pad "53" smd rect
			(at -2.050034 -19.12493 90)
			(size 0.519938 1.4986)
			(layers "F.Cu" "F.Mask" "F.Paste")
			(net "M_F_CPU1_SA_CB<1>")
		)
		(pad "54" smd rect
			(at -2.050034 -18.275046 90)
			(size 0.519938 1.4986)
			(layers "F.Cu" "F.Mask" "F.Paste")
			(net "GND")
		)
		(pad "55" smd rect
			(at -2.050034 -17.424908 90)
			(size 0.519938 1.4986)
			(layers "F.Cu" "F.Mask" "F.Paste")
			(net "M_F_CPU1_SA_DQS_DP<4>")
		)
		(pad "56" smd rect
			(at -2.050034 -16.575024 90)
			(size 0.519938 1.4986)
			(layers "F.Cu" "F.Mask" "F.Paste")
			(net "M_F_CPU1_SA_DQS_DN<4>")
		)
		(pad "57" smd rect
			(at -2.050034 -15.724886 90)
			(size 0.519938 1.4986)
			(layers "F.Cu" "F.Mask" "F.Paste")
			(net "GND")
		)
		(pad "58" smd rect
			(at -2.050034 -14.875002 90)
			(size 0.519938 1.4986)
			(layers "F.Cu" "F.Mask" "F.Paste")
			(net "M_F_CPU1_SA_CB<4>")
		)
		(pad "59" smd rect
			(at -2.050034 -14.025118 90)
			(size 0.519938 1.4986)
			(layers "F.Cu" "F.Mask" "F.Paste")
			(net "GND")
		)
		(pad "60" smd rect
			(at -2.050034 -13.17498 90)
			(size 0.519938 1.4986)
			(layers "F.Cu" "F.Mask" "F.Paste")
			(net "M_F_CPU1_SA_CB<5>")
		)
		(pad "61" smd rect
			(at -2.050034 -12.325096 90)
			(size 0.519938 1.4986)
			(layers "F.Cu" "F.Mask" "F.Paste")
			(net "GND")
		)
		(pad "62" smd rect
			(at -2.050034 -11.474958 90)
			(size 0.519938 1.4986)
			(layers "F.Cu" "F.Mask" "F.Paste")
			(net "M_F_CPU1_ALERT_N")
		)
		(pad "63" smd rect
			(at -2.050034 -10.625074 90)
			(size 0.519938 1.4986)
			(layers "F.Cu" "F.Mask" "F.Paste")
			(net "GND")
		)
		(pad "64" smd rect
			(at -2.050034 -9.774936 90)
			(size 0.519938 1.4986)
			(layers "F.Cu" "F.Mask" "F.Paste")
			(net "M_F_CPU1_SA_CS_N<0>")
		)
		(pad "65" smd rect
			(at -2.050034 -8.925052 90)
			(size 0.519938 1.4986)
			(layers "F.Cu" "F.Mask" "F.Paste")
			(net "GND")
		)
		(pad "66" smd rect
			(at -2.050034 -8.074914 90)
			(size 0.519938 1.4986)
			(layers "F.Cu" "F.Mask" "F.Paste")
			(net "M_F_CPU1_SA_CA<0>")
		)
		(pad "67" smd rect
			(at -2.050034 -7.22503 90)
			(size 0.519938 1.4986)
			(layers "F.Cu" "F.Mask" "F.Paste")
			(net "GND")
		)
		(pad "68" smd rect
			(at -2.050034 -6.374892 90)
			(size 0.519938 1.4986)
			(layers "F.Cu" "F.Mask" "F.Paste")
			(net "M_F_CPU1_SA_CA<2>")
		)
		(pad "69" smd rect
			(at -2.050034 -5.525008 90)
			(size 0.519938 1.4986)
			(layers "F.Cu" "F.Mask" "F.Paste")
			(net "GND")
		)
		(pad "70" smd rect
			(at -2.050034 -4.675124 90)
			(size 0.519938 1.4986)
			(layers "F.Cu" "F.Mask" "F.Paste")
			(net "M_F_CPU1_SA_CA<4>")
		)
		(pad "71" smd rect
			(at -2.050034 -3.824986 90)
			(size 0.519938 1.4986)
			(layers "F.Cu" "F.Mask" "F.Paste")
			(net "GND")
		)
		(pad "72" smd rect
			(at -2.050034 -2.975102 90)
			(size 0.519938 1.4986)
			(layers "F.Cu" "F.Mask" "F.Paste")
			(net "M_F_CPU1_SA_CA<6>")
		)
		(pad "73" smd rect
			(at -2.050034 -2.124964 90)
			(size 0.519938 1.4986)
			(layers "F.Cu" "F.Mask" "F.Paste")
			(net "GND")
		)
		(pad "74" smd rect
			(at -2.050034 -1.27508 90)
			(size 0.519938 1.4986)
			(layers "F.Cu" "F.Mask" "F.Paste")
			(net "M_F_CPU1_SA_PAR")
		)
		(pad "75" smd rect
			(at -2.050034 -0.424942 90)
			(size 0.519938 1.4986)
			(layers "F.Cu" "F.Mask" "F.Paste")
			(net "GND")
		)
		(pad "76" smd rect
			(at -2.050034 5.525008 90)
			(size 0.519938 1.4986)
			(layers "F.Cu" "F.Mask" "F.Paste")
			(net "M_F_CPU1_SB_CA<0>")
		)
		(pad "77" smd rect
			(at -2.050034 6.374892 90)
			(size 0.519938 1.4986)
			(layers "F.Cu" "F.Mask" "F.Paste")
			(net "GND")
		)
		(pad "78" smd rect
			(at -2.050034 7.22503 90)
			(size 0.519938 1.4986)
			(layers "F.Cu" "F.Mask" "F.Paste")
			(net "M_F_CPU1_SB_CA<2>")
		)
		(pad "79" smd rect
			(at -2.050034 8.074914 90)
			(size 0.519938 1.4986)
			(layers "F.Cu" "F.Mask" "F.Paste")
			(net "GND")
		)
		(pad "80" smd rect
			(at -2.050034 8.925052 90)
			(size 0.519938 1.4986)
			(layers "F.Cu" "F.Mask" "F.Paste")
			(net "M_F_CPU1_SB_CA<4>")
		)
		(pad "81" smd rect
			(at -2.050034 9.774936 90)
			(size 0.519938 1.4986)
			(layers "F.Cu" "F.Mask" "F.Paste")
			(net "GND")
		)
		(pad "82" smd rect
			(at -2.050034 10.625074 90)
			(size 0.519938 1.4986)
			(layers "F.Cu" "F.Mask" "F.Paste")
			(net "M_F_CPU1_SB_CA<6>")
		)
		(pad "83" smd rect
			(at -2.050034 11.474958 90)
			(size 0.519938 1.4986)
			(layers "F.Cu" "F.Mask" "F.Paste")
			(net "GND")
		)
		(pad "84" smd rect
			(at -2.050034 12.325096 90)
			(size 0.519938 1.4986)
			(layers "F.Cu" "F.Mask" "F.Paste")
			(net "M_F_CPU1_SB_CS_N<0>")
		)
		(pad "85" smd rect
			(at -2.050034 13.17498 90)
			(size 0.519938 1.4986)
			(layers "F.Cu" "F.Mask" "F.Paste")
			(net "GND")
		)
		(pad "86" smd rect
			(at -2.050034 14.025118 90)
			(size 0.519938 1.4986)
			(layers "F.Cu" "F.Mask" "F.Paste")
			(net "M_F_CPU1_SA_RSP<0>")
		)
		(pad "87" smd rect
			(at -2.050034 14.875002 90)
			(size 0.519938 1.4986)
			(layers "F.Cu" "F.Mask" "F.Paste")
			(net "M_F_CPU1_SB_RSP<0>")
		)
		(pad "88" smd rect
			(at -2.050034 15.724886 90)
			(size 0.519938 1.4986)
			(layers "F.Cu" "F.Mask" "F.Paste")
			(net "GND")
		)
		(pad "89" smd rect
			(at -2.050034 16.575024 90)
			(size 0.519938 1.4986)
			(layers "F.Cu" "F.Mask" "F.Paste")
			(net "M_F_CPU1_SB_CB<4>")
		)
		(pad "90" smd rect
			(at -2.050034 17.424908 90)
			(size 0.519938 1.4986)
			(layers "F.Cu" "F.Mask" "F.Paste")
			(net "GND")
		)
		(pad "91" smd rect
			(at -2.050034 18.275046 90)
			(size 0.519938 1.4986)
			(layers "F.Cu" "F.Mask" "F.Paste")
			(net "M_F_CPU1_SB_CB<5>")
		)
		(pad "92" smd rect
			(at -2.050034 19.12493 90)
			(size 0.519938 1.4986)
			(layers "F.Cu" "F.Mask" "F.Paste")
			(net "GND")
		)
		(pad "93" smd rect
			(at -2.050034 19.975068 90)
			(size 0.519938 1.4986)
			(layers "F.Cu" "F.Mask" "F.Paste")
			(net "M_F_CPU1_SB_DQS_DP<9>")
		)
		(pad "94" smd rect
			(at -2.050034 20.824952 90)
			(size 0.519938 1.4986)
			(layers "F.Cu" "F.Mask" "F.Paste")
			(net "M_F_CPU1_SB_DQS_DN<9>")
		)
		(pad "95" smd rect
			(at -2.050034 21.67509 90)
			(size 0.519938 1.4986)
			(layers "F.Cu" "F.Mask" "F.Paste")
			(net "GND")
		)
		(pad "96" smd rect
			(at -2.050034 22.524974 90)
			(size 0.519938 1.4986)
			(layers "F.Cu" "F.Mask" "F.Paste")
			(net "M_F_CPU1_SB_CB<0>")
		)
		(pad "97" smd rect
			(at -2.050034 23.375112 90)
			(size 0.519938 1.4986)
			(layers "F.Cu" "F.Mask" "F.Paste")
			(net "GND")
		)
		(pad "98" smd rect
			(at -2.050034 24.224996 90)
			(size 0.519938 1.4986)
			(layers "F.Cu" "F.Mask" "F.Paste")
			(net "M_F_CPU1_SB_CB<1>")
		)
		(pad "99" smd rect
			(at -2.050034 25.07488 90)
			(size 0.519938 1.4986)
			(layers "F.Cu" "F.Mask" "F.Paste")
			(net "GND")
		)
		(pad "100" smd rect
			(at -2.050034 25.925018 90)
			(size 0.519938 1.4986)
			(layers "F.Cu" "F.Mask" "F.Paste")
			(net "M_F_CPU1_SB_DQ<0>")
		)
		(pad "101" smd rect
			(at -2.050034 26.774902 90)
			(size 0.519938 1.4986)
			(layers "F.Cu" "F.Mask" "F.Paste")
			(net "GND")
		)
		(pad "102" smd rect
			(at -2.050034 27.62504 90)
			(size 0.519938 1.4986)
			(layers "F.Cu" "F.Mask" "F.Paste")
			(net "M_F_CPU1_SB_DQ<1>")
		)
		(pad "103" smd rect
			(at -2.050034 28.474924 90)
			(size 0.519938 1.4986)
			(layers "F.Cu" "F.Mask" "F.Paste")
			(net "GND")
		)
		(pad "104" smd rect
			(at -2.050034 29.325062 90)
			(size 0.519938 1.4986)
			(layers "F.Cu" "F.Mask" "F.Paste")
			(net "M_F_CPU1_SB_DQS_DP<0>")
		)
		(pad "105" smd rect
			(at -2.050034 30.174946 90)
			(size 0.519938 1.4986)
			(layers "F.Cu" "F.Mask" "F.Paste")
			(net "M_F_CPU1_SB_DQS_DN<0>")
		)
		(pad "106" smd rect
			(at -2.050034 31.025084 90)
			(size 0.519938 1.4986)
			(layers "F.Cu" "F.Mask" "F.Paste")
			(net "GND")
		)
		(pad "107" smd rect
			(at -2.050034 31.874968 90)
			(size 0.519938 1.4986)
			(layers "F.Cu" "F.Mask" "F.Paste")
			(net "M_F_CPU1_SB_DQ<4>")
		)
		(pad "108" smd rect
			(at -2.050034 32.725106 90)
			(size 0.519938 1.4986)
			(layers "F.Cu" "F.Mask" "F.Paste")
			(net "GND")
		)
		(pad "109" smd rect
			(at -2.050034 33.57499 90)
			(size 0.519938 1.4986)
			(layers "F.Cu" "F.Mask" "F.Paste")
			(net "M_F_CPU1_SB_DQ<5>")
		)
		(pad "110" smd rect
			(at -2.050034 34.425128 90)
			(size 0.519938 1.4986)
			(layers "F.Cu" "F.Mask" "F.Paste")
			(net "GND")
		)
		(pad "111" smd rect
			(at -2.050034 35.275012 90)
			(size 0.519938 1.4986)
			(layers "F.Cu" "F.Mask" "F.Paste")
			(net "M_F_CPU1_SB_DQ<8>")
		)
		(pad "112" smd rect
			(at -2.050034 36.124896 90)
			(size 0.519938 1.4986)
			(layers "F.Cu" "F.Mask" "F.Paste")
			(net "GND")
		)
		(pad "113" smd rect
			(at -2.050034 36.975034 90)
			(size 0.519938 1.4986)
			(layers "F.Cu" "F.Mask" "F.Paste")
			(net "M_F_CPU1_SB_DQ<9>")
		)
	)
)
